# T6G (Grand Teton) — schematic netlist excerpt (pin names and nets, part order shuffled) for the footprints in the layout excerpt that follows; sources: Cadence DE-HDL packaged netlist, KiCad conversion of 04192023_DAF0TMB3IC0_F0TG_MB_C_brd_V02_OCP.brd

H93  HOLE  EMPTY  pkg TH  page 230 : \1\ = GND
R210  Q_RES  0 5% CHIP  pkg 0402LF  page 80 : A = SMB_2_PLD_3V3AUX_SCL_R1 ; B = SMB_2_PLD_3V3AUX_SCL_R2
R1428  Q_RES  1K 1% CHIP  pkg 0201LF  page 185 : A = P1V8_CPU0_RT_1D ; B = SMB_RT_CPU0_P3_ROM_MUX_1D_SCL
C1506  Q_CAP  0.1UF 16V 10% X7R  pkg C0402  page 172 : A = P3V3_AUX ; B = GND

(kicad_pcb
	(version 20260206)
	(generator "pcbnew")
	(generator_version "10.0")
	(general
		(thickness 1.6)
		(legacy_teardrops no)
	)
	(paper "A4")
	(title_block
		(title "04192023_DAF0TMB3IC0_F0TG_MB_C_brd_V02_OCP.brd")
		(comment 1 "Grand Teton / footprints 374-377 of 8354")
	)
	(layers
		(0 "F.Cu" signal "TOP")
		(4 "In1.Cu" signal "GND")
		(6 "In2.Cu" signal "IN1")
		(8 "In3.Cu" signal "GND1")
		(10 "In4.Cu" signal "IN2")
		(12 "In5.Cu" signal "GND2")
		(14 "In6.Cu" signal "IN3")
		(16 "In7.Cu" signal "GND3")
		(18 "In8.Cu" signal "VCC")
		(20 "In9.Cu" signal "VCC1")
		(22 "In10.Cu" signal "GND4")
		(24 "In11.Cu" signal "IN4")
		(26 "In12.Cu" signal "GND5")
		(28 "In13.Cu" signal "IN5")
		(30 "In14.Cu" signal "GND6")
		(32 "In15.Cu" signal "IN6")
		(34 "In16.Cu" signal "GND7")
		(2 "B.Cu" signal "BOTTOM")
		(9 "F.Adhes" user "F.Adhesive")
		(11 "B.Adhes" user "B.Adhesive")
		(13 "F.Paste" user "Package Geometry/Pastemask Top")
		(15 "B.Paste" user "Package Geometry/Pastemask Bottom")
		(5 "F.SilkS" user "Ref Des/Silkscreen Top")
		(7 "B.SilkS" user "Ref Des/Silkscreen Bottom")
		(1 "F.Mask" user "Board Geometry/Soldermask Top")
		(3 "B.Mask" user "Board Geometry/Soldermask Bottom")
		(17 "Dwgs.User" user "User.Drawings")
		(19 "Cmts.User" user "User.Comments")
		(21 "Eco1.User" user "User.Eco1")
		(23 "Eco2.User" user "User.Eco2")
		(25 "Edge.Cuts" user "Board Geometry/Outline")
		(27 "Margin" user)
		(31 "F.CrtYd" user "Package Geometry/Place Bound Top")
		(29 "B.CrtYd" user "Package Geometry/Place Bound Bottom")
		(35 "F.Fab" user "Ref Des/Assembly Top")
		(33 "B.Fab" user "Ref Des/Assembly Bottom")
	)
	(footprint ""
		(layer "F.Cu")
		(at 268.355318 -103.26624)
		(property "Reference" "C1506"
			(at 0 0 0)
			(layer "F.SilkS")
			(hide yes)
			(effects
				(font
					(size 1.27 1.27)
				)
			)
		)
		(property "Value" ""
			(at 0 0 0)
			(layer "F.Fab")
			(effects
				(font
					(size 1.27 1.27)
				)
			)
		)
		(duplicate_pad_numbers_are_jumpers no)
		(fp_line
			(start -0.7874 -0.4064)
			(end 0.7874 -0.4064)
			(stroke
				(width 0.1524)
				(type default)
			)
			(layer "F.SilkS")
		)
		(fp_line
			(start -0.7874 0.4064)
			(end -0.7874 -0.4064)
			(stroke
				(width 0.1524)
				(type default)
			)
			(layer "F.SilkS")
		)
		(fp_line
			(start 0.7874 -0.4064)
			(end 0.7874 0.4064)
			(stroke
				(width 0.1524)
				(type default)
			)
			(layer "F.SilkS")
		)
		(fp_line
			(start 0.7874 0.4064)
			(end -0.7874 0.4064)
			(stroke
				(width 0.1524)
				(type default)
			)
			(layer "F.SilkS")
		)
		(fp_line
			(start -0.67945 -0.305054)
			(end -0.12065 -0.305054)
			(stroke
				(width 0.1)
				(type default)
			)
			(layer "F.Fab")
		)
		(fp_line
			(start -0.67945 0.3048)
			(end -0.67945 -0.305054)
			(stroke
				(width 0.1)
				(type default)
			)
			(layer "F.Fab")
		)
		(fp_line
			(start -0.12065 -0.305054)
			(end -0.12065 -0.2794)
			(stroke
				(width 0.1)
				(type default)
			)
			(layer "F.Fab")
		)
		(fp_line
			(start -0.12065 -0.2794)
			(end 0.12065 -0.2794)
			(stroke
				(width 0.1)
				(type default)
			)
			(layer "F.Fab")
		)
		(fp_line
			(start -0.12065 0.2794)
			(end -0.12065 0.3048)
			(stroke
				(width 0.1)
				(type default)
			)
			(layer "F.Fab")
		)
		(fp_line
			(start -0.12065 0.3048)
			(end -0.67945 0.3048)
			(stroke
				(width 0.1)
				(type default)
			)
			(layer "F.Fab")
		)
		(fp_line
			(start 0.120396 0.2794)
			(end -0.12065 0.2794)
			(stroke
				(width 0.1)
				(type default)
			)
			(layer "F.Fab")
		)
		(fp_line
			(start 0.120396 0.3048)
			(end 0.120396 0.2794)
			(stroke
				(width 0.1)
				(type default)
			)
			(layer "F.Fab")
		)
		(fp_line
			(start 0.12065 -0.3048)
			(end 0.67945 -0.3048)
			(stroke
				(width 0.1)
				(type default)
			)
			(layer "F.Fab")
		)
		(fp_line
			(start 0.12065 -0.2794)
			(end 0.12065 -0.3048)
			(stroke
				(width 0.1)
				(type default)
			)
			(layer "F.Fab")
		)
		(fp_line
			(start 0.67945 -0.3048)
			(end 0.67945 0.3048)
			(stroke
				(width 0.1)
				(type default)
			)
			(layer "F.Fab")
		)
		(fp_line
			(start 0.67945 0.3048)
			(end 0.120396 0.3048)
			(stroke
				(width 0.1)
				(type default)
			)
			(layer "F.Fab")
		)
		(pad "1" smd circle
			(at -0.40005 0)
			(size 0 0)
			(layers "F.Cu" "F.Mask" "F.Paste")
			(net "P3V3_AUX")
		)
		(pad "2" smd circle
			(at 0.40005 0)
			(size 0 0)
			(layers "F.Cu" "F.Mask" "F.Paste")
			(net "GND")
		)
	)
	(footprint ""
		(layer "F.Cu")
		(at 94.899988 -22.29993)
		(property "Reference" "H93"
			(at -5.235702 -5.709666 0)
			(unlocked yes)
			(layer "F.SilkS")
			(effects
				(font
					(size 0.7874 0.5842)
					(thickness 0.1524)
				)
				(justify left)
			)
		)
		(property "Value" ""
			(at 0 0 0)
			(layer "F.Fab")
			(effects
				(font
					(size 1.27 1.27)
				)
			)
		)
		(duplicate_pad_numbers_are_jumpers no)
		(pad "1" thru_hole circle
			(at 0 0)
			(size 10.0076 10.0076)
			(drill 5.6134)
			(layers "*.Cu" "*.Mask")
			(remove_unused_layers no)
			(net "GND")
			(clearance -1.9431)
		)
	)
	(footprint ""
		(layer "F.Cu")
		(at 365.789718 -429.075342)
		(property "Reference" "R1428"
			(at 0 0 0)
			(layer "F.SilkS")
			(hide yes)
			(effects
				(font
					(size 1.27 1.27)
				)
			)
		)
		(property "Value" ""
			(at 0 0 0)
			(layer "F.Fab")
			(effects
				(font
					(size 1.27 1.27)
				)
			)
		)
		(duplicate_pad_numbers_are_jumpers no)
		(fp_line
			(start -0.32512 -0.175006)
			(end 0.32512 -0.175006)
			(stroke
				(width 0.1)
				(type default)
			)
			(layer "F.Fab")
		)
		(fp_line
			(start -0.32512 0.175006)
			(end -0.32512 -0.175006)
			(stroke
				(width 0.1)
				(type default)
			)
			(layer "F.Fab")
		)
		(fp_line
			(start 0.32512 -0.175006)
			(end 0.32512 0.175006)
			(stroke
				(width 0.1)
				(type default)
			)
			(layer "F.Fab")
		)
		(fp_line
			(start 0.32512 0.175006)
			(end -0.32512 0.175006)
			(stroke
				(width 0.1)
				(type default)
			)
			(layer "F.Fab")
		)
		(pad "1" smd rect
			(at -0.2667 0)
			(size 0.3048 0.381)
			(layers "F.Cu" "F.Mask" "F.Paste")
			(net "P1V8_CPU0_RT_1D")
		)
		(pad "2" smd rect
			(at 0.2667 0 180)
			(size 0.3048 0.381)
			(layers "F.Cu" "F.Mask" "F.Paste")
			(net "SMB_RT_CPU0_P3_ROM_MUX_1D_SCL")
		)
	)
	(footprint ""
		(layer "F.Cu")
		(at 171.196 -117.312948)
		(property "Reference" "R210"
			(at 0 0 0)
			(layer "F.SilkS")
			(hide yes)
			(effects
				(font
					(size 1.27 1.27)
				)
			)
		)
		(property "Value" ""
			(at 0 0 0)
			(layer "F.Fab")
			(effects
				(font
					(size 1.27 1.27)
				)
			)
		)
		(duplicate_pad_numbers_are_jumpers no)
		(fp_line
			(start -0.7874 -0.4064)
			(end 0.7874 -0.4064)
			(stroke
				(width 0.1524)
				(type default)
			)
			(layer "F.SilkS")
		)
		(fp_line
			(start -0.7874 0.4064)
			(end -0.7874 -0.4064)
			(stroke
				(width 0.1524)
				(type default)
			)
			(layer "F.SilkS")
		)
		(fp_line
			(start 0.7874 -0.4064)
			(end 0.7874 0.4064)
			(stroke
				(width 0.1524)
				(type default)
			)
			(layer "F.SilkS")
		)
		(fp_line
			(start 0.7874 0.4064)
			(end -0.7874 0.4064)
			(stroke
				(width 0.1524)
				(type default)
			)
			(layer "F.SilkS")
		)
		(fp_line
			(start -0.67945 -0.305054)
			(end -0.12065 -0.305054)
			(stroke
				(width 0.1)
				(type default)
			)
			(layer "F.Fab")
		)
		(fp_line
			(start -0.67945 0.3048)
			(end -0.67945 -0.305054)
			(stroke
				(width 0.1)
				(type default)
			)
			(layer "F.Fab")
		)
		(fp_line
			(start -0.12065 -0.305054)
			(end -0.12065 -0.2794)
			(stroke
				(width 0.1)
				(type default)
			)
			(layer "F.Fab")
		)
		(fp_line
			(start -0.12065 -0.2794)
			(end 0.12065 -0.2794)
			(stroke
				(width 0.1)
				(type default)
			)
			(layer "F.Fab")
		)
		(fp_line
			(start -0.12065 0.2794)
			(end -0.12065 0.3048)
			(stroke
				(width 0.1)
				(type default)
			)
			(layer "F.Fab")
		)
		(fp_line
			(start -0.12065 0.3048)
			(end -0.67945 0.3048)
			(stroke
				(width 0.1)
				(type default)
			)
			(layer "F.Fab")
		)
		(fp_line
			(start 0.120396 0.2794)
			(end -0.12065 0.2794)
			(stroke
				(width 0.1)
				(type default)
			)
			(layer "F.Fab")
		)
		(fp_line
			(start 0.120396 0.3048)
			(end 0.120396 0.2794)
			(stroke
				(width 0.1)
				(type default)
			)
			(layer "F.Fab")
		)
		(fp_line
			(start 0.12065 -0.3048)
			(end 0.67945 -0.3048)
			(stroke
				(width 0.1)
				(type default)
			)
			(layer "F.Fab")
		)
		(fp_line
			(start 0.12065 -0.2794)
			(end 0.12065 -0.3048)
			(stroke
				(width 0.1)
				(type default)
			)
			(layer "F.Fab")
		)
		(fp_line
			(start 0.67945 -0.3048)
			(end 0.67945 0.3048)
			(stroke
				(width 0.1)
				(type default)
			)
			(layer "F.Fab")
		)
		(fp_line
			(start 0.67945 0.3048)
			(end 0.120396 0.3048)
			(stroke
				(width 0.1)
				(type default)
			)
			(layer "F.Fab")
		)
		(pad "1" smd circle
			(at -0.40005 0)
			(size 0 0)
			(layers "F.Cu" "F.Mask" "F.Paste")
			(net "SMB_2_PLD_3V3AUX_SCL_R1")
		)
		(pad "2" smd circle
			(at 0.40005 0)
			(size 0 0)
			(layers "F.Cu" "F.Mask" "F.Paste")
			(net "SMB_2_PLD_3V3AUX_SCL_R2")
		)
	)
)
